(kicad_pcb
	(version 20260206)
	(generator "pcbnew")
	(generator_version "10.0")
	(general
		(thickness 1.6)
		(legacy_teardrops no)
	)
	(paper "A4")
	(title_block
		(title "Bryce Canyon_R.DPB_16317-1_OCP.brd")
		(comment 1 "Bryce Canyon / footprints 780-785 of 2099")
	)
	(layers
		(0 "F.Cu" signal "TOP")
		(4 "In1.Cu" signal "L2GND")
		(6 "In2.Cu" signal "L3")
		(8 "In3.Cu" signal "L4VCC")
		(10 "In4.Cu" signal "L5VCC")
		(12 "In5.Cu" signal "L6")
		(14 "In6.Cu" signal "L7GND")
		(2 "B.Cu" signal "BOTTOM")
		(9 "F.Adhes" user "F.Adhesive")
		(11 "B.Adhes" user "B.Adhesive")
		(13 "F.Paste" user "Package Geometry/Pastemask Top")
		(15 "B.Paste" user "Package Geometry/Pastemask Bottom")
		(5 "F.SilkS" user "Ref Des/Silkscreen Top")
		(7 "B.SilkS" user "Ref Des/Silkscreen Bottom")
		(1 "F.Mask" user "Board Geometry/Soldermask Top")
		(3 "B.Mask" user "Board Geometry/Soldermask Bottom")
		(17 "Dwgs.User" user "User.Drawings")
		(19 "Cmts.User" user "User.Comments")
		(21 "Eco1.User" user "User.Eco1")
		(23 "Eco2.User" user "User.Eco2")
		(25 "Edge.Cuts" user "Board Geometry/Outline")
		(27 "Margin" user)
		(31 "F.CrtYd" user "Package Geometry/Place Bound Top")
		(29 "B.CrtYd" user "Package Geometry/Place Bound Bottom")
		(35 "F.Fab" user "Ref Des/Assembly Top")
		(33 "B.Fab" user "Ref Des/Assembly Bottom")
	)
	(footprint ""
		(layer "F.Cu")
		(at 320.592196 -371.0432 180)
		(property "Reference" "U51"
			(at 0 0 180)
			(layer "F.SilkS")
			(hide yes)
			(effects
				(font
					(size 1.27 1.27)
				)
			)
		)
		(property "Value" "SN74LVC1G08DCKR-GP"
			(at -2.3368 -8.6868 180)
			(unlocked yes)
			(layer "F.Fab")
			(hide yes)
			(effects
				(font
					(size 1.016 1.016)
					(thickness 0.1524)
				)
			)
		)
		(property "Device Type" "SC70-5H44"
			(at -2.3114 -10.414 180)
			(unlocked yes)
			(layer "F.Fab")
			(hide yes)
			(effects
				(font
					(size 1.016 1.016)
					(thickness 0.1524)
				)
			)
		)
		(duplicate_pad_numbers_are_jumpers no)
		(fp_line
			(start 1.3843 -1.8034)
			(end 1.3843 -1.1176)
			(stroke
				(width 0.3302)
				(type default)
			)
			(layer "F.SilkS")
		)
		(fp_line
			(start 1.27 1.7018)
			(end -1.27 1.7018)
			(stroke
				(width 0.1524)
				(type default)
			)
			(layer "F.SilkS")
		)
		(fp_line
			(start 1.27 -1.7018)
			(end 1.27 1.7018)
			(stroke
				(width 0.1524)
				(type default)
			)
			(layer "F.SilkS")
		)
		(fp_line
			(start 0.6604 -1.8034)
			(end 1.3843 -1.8034)
			(stroke
				(width 0.3302)
				(type default)
			)
			(layer "F.SilkS")
		)
		(fp_line
			(start -1.27 1.7018)
			(end -1.27 -1.7018)
			(stroke
				(width 0.1524)
				(type default)
			)
			(layer "F.SilkS")
		)
		(fp_line
			(start -1.27 -1.7018)
			(end 1.27 -1.7018)
			(stroke
				(width 0.1524)
				(type default)
			)
			(layer "F.SilkS")
		)
		(fp_rect
			(start -1.524 1.9558)
			(end 1.524 -1.9558)
			(stroke
				(width 0)
				(type default)
			)
			(fill no)
			(layer "F.CrtYd")
		)
		(fp_poly
			(pts
				(xy -1.524 -1.9558) (xy 1.524 -1.9558) (xy 1.524 1.9558) (xy -1.524 1.9558)
			)
			(stroke
				(width 0)
				(type default)
			)
			(fill no)
			(layer "F.Fab")
		)
		(pad "1" smd rect
			(at 0.65024 -0.8255 180)
			(size 0.4064 1.2192)
			(layers "F.Cu" "F.Mask" "F.Paste")
			(net "RDPB_FAN_LED2")
		)
		(pad "2" smd rect
			(at 0 -0.8255 180)
			(size 0.4064 1.2192)
			(layers "F.Cu" "F.Mask" "F.Paste")
			(net "FDPB_FAN_LED2")
		)
		(pad "3" smd rect
			(at -0.65024 -0.8255 180)
			(size 0.4064 1.2192)
			(layers "F.Cu" "F.Mask" "F.Paste")
			(net "GND")
		)
		(pad "4" smd rect
			(at -0.65024 0.8255 180)
			(size 0.4064 1.2192)
			(layers "F.Cu" "F.Mask" "F.Paste")
			(net "FAN_LED2")
		)
		(pad "5" smd rect
			(at 0.65024 0.8255 180)
			(size 0.4064 1.2192)
			(layers "F.Cu" "F.Mask" "F.Paste")
			(net "P3V3_IN")
		)
	)
	(footprint ""
		(layer "F.Cu")
		(at 49.55286 -118.310406 -90)
		(property "Reference" "C641"
			(at 0 0 270)
			(layer "F.SilkS")
			(hide yes)
			(effects
				(font
					(size 1.27 1.27)
				)
			)
		)
		(property "Value" "SC1U16V3KX-5GP"
			(at 0 -2.8194 270)
			(unlocked yes)
			(layer "F.Fab")
			(hide yes)
			(effects
				(font
					(size 1.016 1.016)
					(thickness 0.1524)
				)
			)
		)
		(property "Device Type" "C603H36"
			(at 0 -4.3434 270)
			(unlocked yes)
			(layer "F.Fab")
			(hide yes)
			(effects
				(font
					(size 1.016 1.016)
					(thickness 0.1524)
				)
			)
		)
		(duplicate_pad_numbers_are_jumpers no)
		(fp_line
			(start 0.508 0)
			(end -0.508 0)
			(stroke
				(width 0.2032)
				(type default)
			)
			(layer "F.SilkS")
		)
		(fp_rect
			(start -0.5842 1.3335)
			(end 0.5842 -1.3335)
			(stroke
				(width 0)
				(type default)
			)
			(fill no)
			(layer "F.CrtYd")
		)
		(fp_rect
			(start -0.5842 1.3335)
			(end 0.5842 -1.3335)
			(stroke
				(width 0)
				(type default)
			)
			(fill no)
			(layer "F.Fab")
		)
		(pad "1" smd custom
			(at 0 -0.762 270)
			(size 0.2159 0.2159)
			(layers "F.Cu" "F.Mask" "F.Paste")
			(net "P5V_B_2_EN_R")
			(options
				(clearance outline)
				(anchor circle)
			)
			(primitives
				(gr_poly
					(pts
						(arc
							(start -0.3302 -0.4318)
							(mid -0.402042 -0.402042)
							(end -0.4318 -0.3302)
						)
						(arc
							(start -0.4318 0.3302)
							(mid -0.402042 0.402042)
							(end -0.3302 0.4318)
						)
						(arc
							(start 0.3302 0.4318)
							(mid 0.402042 0.402042)
							(end 0.4318 0.3302)
						)
						(arc
							(start 0.4318 -0.3302)
							(mid 0.402042 -0.402042)
							(end 0.3302 -0.4318)
						)
					)
					(width 0)
					(fill yes)
				)
			)
		)
		(pad "2" smd custom
			(at 0 0.762 270)
			(size 0.2159 0.2159)
			(layers "F.Cu" "F.Mask" "F.Paste")
			(net "GND")
			(options
				(clearance outline)
				(anchor circle)
			)
			(primitives
				(gr_poly
					(pts
						(arc
							(start -0.3302 -0.4318)
							(mid -0.402042 -0.402042)
							(end -0.4318 -0.3302)
						)
						(arc
							(start -0.4318 0.3302)
							(mid -0.402042 0.402042)
							(end -0.3302 0.4318)
						)
						(arc
							(start 0.3302 0.4318)
							(mid 0.402042 0.402042)
							(end 0.4318 0.3302)
						)
						(arc
							(start 0.4318 -0.3302)
							(mid 0.402042 -0.402042)
							(end 0.3302 -0.4318)
						)
					)
					(width 0)
					(fill yes)
				)
			)
		)
	)
	(footprint ""
		(layer "F.Cu")
		(at 331.0382 -16.2306 -90)
		(property "Reference" "C428"
			(at 0 0 270)
			(layer "F.SilkS")
			(hide yes)
			(effects
				(font
					(size 1.27 1.27)
				)
			)
		)
		(property "Value" "SCD033U25V2KX-GP"
			(at 1.1811 -2.7051 270)
			(unlocked yes)
			(layer "F.Fab")
			(hide yes)
			(effects
				(font
					(size 1.016 1.016)
					(thickness 0.1524)
				)
			)
		)
		(property "Device Type" "C402H22"
			(at 1.1811 -4.2291 270)
			(unlocked yes)
			(layer "F.Fab")
			(hide yes)
			(effects
				(font
					(size 1.016 1.016)
					(thickness 0.1524)
				)
			)
		)
		(duplicate_pad_numbers_are_jumpers no)
		(fp_rect
			(start -0.4318 0.9525)
			(end 0.4318 -0.9525)
			(stroke
				(width 0)
				(type default)
			)
			(fill no)
			(layer "F.CrtYd")
		)
		(fp_rect
			(start -0.4318 0.9525)
			(end 0.4318 -0.9525)
			(stroke
				(width 0)
				(type default)
			)
			(fill no)
			(layer "F.Fab")
		)
		(pad "1" smd custom
			(at 0 -0.4445 270)
			(size 0.1524 0.1524)
			(layers "F.Cu" "F.Mask" "F.Paste")
			(net "SW_HDD_P30")
			(options
				(clearance outline)
				(anchor circle)
			)
			(primitives
				(gr_poly
					(pts
						(arc
							(start 0.3048 -0.2032)
							(mid 0.275042 -0.275042)
							(end 0.2032 -0.3048)
						)
						(arc
							(start -0.2032 -0.3048)
							(mid -0.275042 -0.275042)
							(end -0.3048 -0.2032)
						)
						(arc
							(start -0.3048 0.2032)
							(mid -0.275042 0.275042)
							(end -0.2032 0.3048)
						)
						(arc
							(start 0.2032 0.3048)
							(mid 0.275042 0.275042)
							(end 0.3048 0.2032)
						)
					)
					(width 0)
					(fill yes)
				)
			)
		)
		(pad "2" smd custom
			(at 0 0.4445 270)
			(size 0.1524 0.1524)
			(layers "F.Cu" "F.Mask" "F.Paste")
			(net "GND")
			(options
				(clearance outline)
				(anchor circle)
			)
			(primitives
				(gr_poly
					(pts
						(arc
							(start 0.3048 -0.2032)
							(mid 0.275042 -0.275042)
							(end 0.2032 -0.3048)
						)
						(arc
							(start -0.2032 -0.3048)
							(mid -0.275042 -0.275042)
							(end -0.3048 -0.2032)
						)
						(arc
							(start -0.3048 0.2032)
							(mid -0.275042 0.275042)
							(end -0.2032 0.3048)
						)
						(arc
							(start 0.2032 0.3048)
							(mid 0.275042 0.275042)
							(end 0.3048 0.2032)
						)
					)
					(width 0)
					(fill yes)
				)
			)
		)
	)
	(footprint ""
		(layer "F.Cu")
		(at 466.909404 -374.2309 90)
		(property "Reference" "R977"
			(at 0 0 90)
			(layer "F.SilkS")
			(hide yes)
			(effects
				(font
					(size 1.27 1.27)
				)
			)
		)
		(property "Value" "1KR5F-1-GP"
			(at 0 -8.9535 90)
			(unlocked yes)
			(layer "F.Fab")
			(hide yes)
			(effects
				(font
					(size 1.27 1.016)
					(thickness 0.1524)
				)
			)
		)
		(property "Device Type" "R805H24"
			(at 0 -10.6299 90)
			(unlocked yes)
			(layer "F.Fab")
			(hide yes)
			(effects
				(font
					(size 1.27 1.016)
					(thickness 0.1524)
				)
			)
		)
		(duplicate_pad_numbers_are_jumpers no)
		(fp_line
			(start 0.889 -1.7018)
			(end -0.889 -1.7018)
			(stroke
				(width 0.1524)
				(type default)
			)
			(layer "F.SilkS")
		)
		(fp_line
			(start 0.889 -1.7018)
			(end 0.889 -0.381)
			(stroke
				(width 0.1524)
				(type default)
			)
			(layer "F.SilkS")
		)
		(fp_line
			(start -0.889 -1.7018)
			(end -0.889 0.2794)
			(stroke
				(width 0.1524)
				(type default)
			)
			(layer "F.SilkS")
		)
		(fp_line
			(start -0.889 0.0762)
			(end -0.889 1.7018)
			(stroke
				(width 0.1524)
				(type default)
			)
			(layer "F.SilkS")
		)
		(fp_line
			(start 0.889 1.7018)
			(end 0.889 -0.508)
			(stroke
				(width 0.1524)
				(type default)
			)
			(layer "F.SilkS")
		)
		(fp_line
			(start -0.889 1.7018)
			(end 0.889 1.7018)
			(stroke
				(width 0.1524)
				(type default)
			)
			(layer "F.SilkS")
		)
		(fp_poly
			(pts
				(xy 0.9652 -1.778) (xy 0.9652 1.778) (xy -0.9652 1.778) (xy -0.9652 -1.778)
			)
			(stroke
				(width 0)
				(type default)
			)
			(fill no)
			(layer "F.CrtYd")
		)
		(fp_rect
			(start -0.9652 1.778)
			(end 0.9652 -1.778)
			(stroke
				(width 0)
				(type default)
			)
			(fill no)
			(layer "F.Fab")
		)
		(pad "1" smd rect
			(at 0 -0.9652 90)
			(size 1.397 1.143)
			(layers "F.Cu" "F.Mask" "F.Paste")
			(net "FAN_YELLOW_3")
		)
		(pad "2" smd rect
			(at 0 0.9652 90)
			(size 1.397 1.143)
			(layers "F.Cu" "F.Mask" "F.Paste")
			(net "FAN_LED_YELLOW_3")
		)
	)
	(footprint ""
		(layer "F.Cu")
		(at 302.212248 -352.672142 -90)
		(property "Reference" "U17"
			(at 0 0 270)
			(layer "F.SilkS")
			(hide yes)
			(effects
				(font
					(size 1.27 1.27)
				)
			)
		)
		(property "Value" "SN74CBTLV3245APWR-GP"
			(at -0.889 -6.2738 270)
			(unlocked yes)
			(layer "F.Fab")
			(hide yes)
			(effects
				(font
					(size 1.016 1.016)
					(thickness 0.1524)
				)
			)
		)
		(property "Device Type" "TSOIC20H48"
			(at -0.9144 -7.8994 270)
			(unlocked yes)
			(layer "F.Fab")
			(hide yes)
			(effects
				(font
					(size 1.016 1.016)
					(thickness 0.1524)
				)
			)
		)
		(duplicate_pad_numbers_are_jumpers no)
		(fp_line
			(start -3.556 4.064)
			(end -3.556 1.778)
			(stroke
				(width 0.508)
				(type default)
			)
			(layer "F.SilkS")
		)
		(fp_line
			(start -3.556 1.397)
			(end -3.556 1.778)
			(stroke
				(width 0.2032)
				(type default)
			)
			(layer "F.SilkS")
		)
		(fp_line
			(start 3.175 1.397)
			(end -3.556 1.397)
			(stroke
				(width 0.2032)
				(type default)
			)
			(layer "F.SilkS")
		)
		(fp_line
			(start -2.667 0)
			(end -3.556 0.889)
			(stroke
				(width 0.2032)
				(type default)
			)
			(layer "F.SilkS")
		)
		(fp_line
			(start -2.667 0)
			(end -3.556 -0.889)
			(stroke
				(width 0.2032)
				(type default)
			)
			(layer "F.SilkS")
		)
		(fp_line
			(start -3.556 -1.397)
			(end -3.556 4.064)
			(stroke
				(width 0.2032)
				(type default)
			)
			(layer "F.SilkS")
		)
		(fp_line
			(start -3.556 -1.397)
			(end 3.175 -1.397)
			(stroke
				(width 0.2032)
				(type default)
			)
			(layer "F.SilkS")
		)
		(fp_line
			(start 3.175 -1.397)
			(end 3.175 1.397)
			(stroke
				(width 0.2032)
				(type default)
			)
			(layer "F.SilkS")
		)
		(fp_poly
			(pts
				(xy -3.25628 -1.8542) (xy 3.25628 -1.8542) (xy 3.25628 1.8542) (xy -3.25628 1.8542)
			)
			(stroke
				(width 0)
				(type default)
			)
			(fill yes)
			(layer "F.SilkS")
		)
		(fp_rect
			(start -3.556 3.81)
			(end 3.556 -3.81)
			(stroke
				(width 0)
				(type default)
			)
			(fill no)
			(layer "F.CrtYd")
		)
		(fp_poly
			(pts
				(xy -3.556 -3.81) (xy 3.556 -3.81) (xy 3.556 3.81) (xy -3.556 3.81)
			)
			(stroke
				(width 0)
				(type default)
			)
			(fill no)
			(layer "F.Fab")
		)
		(pad "1" smd rect
			(at -2.92608 2.8194 270)
			(size 0.3556 1.524)
			(layers "F.Cu" "F.Mask" "F.Paste")
			(net "Net_106")
		)
		(pad "2" smd rect
			(at -2.27584 2.8194 270)
			(size 0.3556 1.524)
			(layers "F.Cu" "F.Mask" "F.Paste")
			(net "FANTACH_B_F0")
		)
		(pad "3" smd rect
			(at -1.6256 2.8194 270)
			(size 0.3556 1.524)
			(layers "F.Cu" "F.Mask" "F.Paste")
			(net "FANTACH_B_R0")
		)
		(pad "4" smd rect
			(at -0.97536 2.8194 270)
			(size 0.3556 1.524)
			(layers "F.Cu" "F.Mask" "F.Paste")
			(net "FANTACH_B_F1")
		)
		(pad "5" smd rect
			(at -0.32512 2.8194 270)
			(size 0.3556 1.524)
			(layers "F.Cu" "F.Mask" "F.Paste")
			(net "FANTACH_B_R1")
		)
		(pad "6" smd rect
			(at 0.32512 2.8194 270)
			(size 0.3556 1.524)
			(layers "F.Cu" "F.Mask" "F.Paste")
			(net "FANTACH_B_F2")
		)
		(pad "7" smd rect
			(at 0.97536 2.8194 270)
			(size 0.3556 1.524)
			(layers "F.Cu" "F.Mask" "F.Paste")
			(net "FANTACH_B_R2")
		)
		(pad "8" smd rect
			(at 1.6256 2.8194 270)
			(size 0.3556 1.524)
			(layers "F.Cu" "F.Mask" "F.Paste")
			(net "FANTACH_B_F3")
		)
		(pad "9" smd rect
			(at 2.27584 2.8194 270)
			(size 0.3556 1.524)
			(layers "F.Cu" "F.Mask" "F.Paste")
			(net "FANTACH_B_R3")
		)
		(pad "10" smd rect
			(at 2.92608 2.8194 270)
			(size 0.3556 1.524)
			(layers "F.Cu" "F.Mask" "F.Paste")
			(net "GND")
		)
		(pad "11" smd rect
			(at 2.92608 -2.8194 270)
			(size 0.3556 1.524)
			(layers "F.Cu" "F.Mask" "F.Paste")
			(net "FANTACH_R3")
		)
		(pad "12" smd rect
			(at 2.27584 -2.8194 270)
			(size 0.3556 1.524)
			(layers "F.Cu" "F.Mask" "F.Paste")
			(net "FANTACH_F3")
		)
		(pad "13" smd rect
			(at 1.6256 -2.8194 270)
			(size 0.3556 1.524)
			(layers "F.Cu" "F.Mask" "F.Paste")
			(net "FANTACH_R2")
		)
		(pad "14" smd rect
			(at 0.97536 -2.8194 270)
			(size 0.3556 1.524)
			(layers "F.Cu" "F.Mask" "F.Paste")
			(net "FANTACH_F2")
		)
		(pad "15" smd rect
			(at 0.32512 -2.8194 270)
			(size 0.3556 1.524)
			(layers "F.Cu" "F.Mask" "F.Paste")
			(net "FANTACH_R1")
		)
		(pad "16" smd rect
			(at -0.32512 -2.8194 270)
			(size 0.3556 1.524)
			(layers "F.Cu" "F.Mask" "F.Paste")
			(net "FANTACH_F1")
		)
		(pad "17" smd rect
			(at -0.97536 -2.8194 270)
			(size 0.3556 1.524)
			(layers "F.Cu" "F.Mask" "F.Paste")
			(net "FANTACH_R0")
		)
		(pad "18" smd rect
			(at -1.6256 -2.8194 270)
			(size 0.3556 1.524)
			(layers "F.Cu" "F.Mask" "F.Paste")
			(net "FANTACH_F0")
		)
		(pad "19" smd rect
			(at -2.27584 -2.8194 270)
			(size 0.3556 1.524)
			(layers "F.Cu" "F.Mask" "F.Paste")
			(net "FANTACH_B_OE_N")
		)
		(pad "20" smd rect
			(at -2.92608 -2.8194 270)
			(size 0.3556 1.524)
			(layers "F.Cu" "F.Mask" "F.Paste")
			(net "P3V3_IN")
		)
	)
	(footprint ""
		(layer "F.Cu")
		(at 37.940996 -364.998 180)
		(property "Reference" "R927"
			(at 0 0 180)
			(layer "F.SilkS")
			(hide yes)
			(effects
				(font
					(size 1.27 1.27)
				)
			)
		)
		(property "Value" "4K7R2F-GP"
			(at 0.064008 -3.993896 180)
			(unlocked yes)
			(layer "F.Fab")
			(hide yes)
			(effects
				(font
					(size 1.016 1.016)
					(thickness 0.1524)
				)
			)
		)
		(property "Device Type" "R402H16"
			(at 0.064008 -5.517896 180)
			(unlocked yes)
			(layer "F.Fab")
			(hide yes)
			(effects
				(font
					(size 1.016 1.016)
					(thickness 0.1524)
				)
			)
		)
		(duplicate_pad_numbers_are_jumpers no)
		(fp_line
			(start 0.508 -0.9398)
			(end -0.508 -0.9398)
			(stroke
				(width 0.1524)
				(type default)
			)
			(layer "F.SilkS")
		)
		(fp_line
			(start -0.508 -0.9398)
			(end -0.508 0.9398)
			(stroke
				(width 0.1524)
				(type default)
			)
			(layer "F.SilkS")
		)
		(fp_rect
			(start -0.508 0.9398)
			(end 0.508 -0.9398)
			(stroke
				(width 0)
				(type default)
			)
			(fill no)
			(layer "F.CrtYd")
		)
		(fp_rect
			(start -0.508 0.9398)
			(end 0.508 -0.9398)
			(stroke
				(width 0)
				(type default)
			)
			(fill no)
			(layer "F.Fab")
		)
		(pad "1" smd custom
			(at 0 -0.4445 180)
			(size 0.1397 0.1397)
			(layers "F.Cu" "F.Mask" "F.Paste")
			(net "P12V_IN")
			(options
				(clearance outline)
				(anchor circle)
			)
			(primitives
				(gr_poly
					(pts
						(arc
							(start -0.1778 -0.2794)
							(mid -0.249642 -0.249642)
							(end -0.2794 -0.1778)
						)
						(arc
							(start -0.2794 0.1778)
							(mid -0.249642 0.249642)
							(end -0.1778 0.2794)
						)
						(arc
							(start 0.1778 0.2794)
							(mid 0.249642 0.249642)
							(end 0.2794 0.1778)
						)
						(arc
							(start 0.2794 -0.1778)
							(mid 0.249642 -0.249642)
							(end 0.1778 -0.2794)
						)
					)
					(width 0)
					(fill yes)
				)
			)
		)
		(pad "2" smd custom
			(at 0 0.4445 180)
			(size 0.1397 0.1397)
			(layers "F.Cu" "F.Mask" "F.Paste")
			(net "FAN_0_TACH1")
			(options
				(clearance outline)
				(anchor circle)
			)
			(primitives
				(gr_poly
					(pts
						(arc
							(start -0.1778 -0.2794)
							(mid -0.249642 -0.249642)
							(end -0.2794 -0.1778)
						)
						(arc
							(start -0.2794 0.1778)
							(mid -0.249642 0.249642)
							(end -0.1778 0.2794)
						)
						(arc
							(start 0.1778 0.2794)
							(mid 0.249642 0.249642)
							(end 0.2794 0.1778)
						)
						(arc
							(start 0.2794 -0.1778)
							(mid 0.249642 -0.249642)
							(end 0.1778 -0.2794)
						)
					)
					(width 0)
					(fill yes)
				)
			)
		)
	)
)
